(kicad_pcb
	(version 20260206)
	(generator "pcbnew")
	(generator_version "10.0")
	(general
		(thickness 1.6)
		(legacy_teardrops no)
	)
	(paper "A4")
	(title_block
		(title "9054_F0T_PDB_BD_GPU_F_V04_1213_1550_OCP.brd")
		(comment 1 "Grand Teton / footprints 476-481 of 608")
	)
	(layers
		(0 "F.Cu" signal "TOP")
		(4 "In1.Cu" signal "GND")
		(6 "In2.Cu" signal "IN1")
		(8 "In3.Cu" signal "GND1")
		(10 "In4.Cu" signal "VCC")
		(12 "In5.Cu" signal "VCC1")
		(14 "In6.Cu" signal "GND2")
		(16 "In7.Cu" signal "IN2")
		(18 "In8.Cu" signal "GND3")
		(2 "B.Cu" signal "BOTTOM")
		(9 "F.Adhes" user "F.Adhesive")
		(11 "B.Adhes" user "B.Adhesive")
		(13 "F.Paste" user "Package Geometry/Pastemask Top")
		(15 "B.Paste" user "Package Geometry/Pastemask Bottom")
		(5 "F.SilkS" user "Ref Des/Silkscreen Top")
		(7 "B.SilkS" user "Ref Des/Silkscreen Bottom")
		(1 "F.Mask" user "Board Geometry/Soldermask Top")
		(3 "B.Mask" user "Board Geometry/Soldermask Bottom")
		(17 "Dwgs.User" user "User.Drawings")
		(19 "Cmts.User" user "User.Comments")
		(21 "Eco1.User" user "User.Eco1")
		(23 "Eco2.User" user "User.Eco2")
		(25 "Edge.Cuts" user "Board Geometry/Outline")
		(27 "Margin" user)
		(31 "F.CrtYd" user "Package Geometry/Place Bound Top")
		(29 "B.CrtYd" user "Package Geometry/Place Bound Bottom")
		(35 "F.Fab" user "Ref Des/Assembly Top")
		(33 "B.Fab" user "Ref Des/Assembly Bottom")
	)
	(footprint ""
		(layer "B.Cu")
		(at 107.188 -54.864 90)
		(property "Reference" "PR7000"
			(at 0 0 90)
			(layer "B.SilkS")
			(hide yes)
			(effects
				(font
					(size 1.27 1.27)
				)
				(justify mirror)
			)
		)
		(property "Value" ""
			(at 0 0 90)
			(layer "B.Fab")
			(effects
				(font
					(size 1.27 1.27)
				)
				(justify mirror)
			)
		)
		(duplicate_pad_numbers_are_jumpers no)
		(fp_line
			(start 0.7874 -0.4064)
			(end -0.7874 -0.4064)
			(stroke
				(width 0.1524)
				(type default)
			)
			(layer "B.SilkS")
		)
		(fp_line
			(start -0.7874 -0.4064)
			(end -0.7874 0.4064)
			(stroke
				(width 0.1524)
				(type default)
			)
			(layer "B.SilkS")
		)
		(fp_line
			(start 0.7874 0.4064)
			(end 0.7874 -0.4064)
			(stroke
				(width 0.1524)
				(type default)
			)
			(layer "B.SilkS")
		)
		(fp_line
			(start -0.7874 0.4064)
			(end 0.7874 0.4064)
			(stroke
				(width 0.1524)
				(type default)
			)
			(layer "B.SilkS")
		)
		(fp_line
			(start 0.67945 -0.305054)
			(end 0.12065 -0.305054)
			(stroke
				(width 0.1)
				(type default)
			)
			(layer "B.Fab")
		)
		(fp_line
			(start 0.12065 -0.305054)
			(end 0.12065 -0.2794)
			(stroke
				(width 0.1)
				(type default)
			)
			(layer "B.Fab")
		)
		(fp_line
			(start -0.12065 -0.3048)
			(end -0.67945 -0.3048)
			(stroke
				(width 0.1)
				(type default)
			)
			(layer "B.Fab")
		)
		(fp_line
			(start -0.67945 -0.3048)
			(end -0.67945 0.3048)
			(stroke
				(width 0.1)
				(type default)
			)
			(layer "B.Fab")
		)
		(fp_line
			(start 0.12065 -0.2794)
			(end -0.12065 -0.2794)
			(stroke
				(width 0.1)
				(type default)
			)
			(layer "B.Fab")
		)
		(fp_line
			(start -0.12065 -0.2794)
			(end -0.12065 -0.3048)
			(stroke
				(width 0.1)
				(type default)
			)
			(layer "B.Fab")
		)
		(fp_line
			(start 0.12065 0.2794)
			(end 0.12065 0.3048)
			(stroke
				(width 0.1)
				(type default)
			)
			(layer "B.Fab")
		)
		(fp_line
			(start -0.120396 0.2794)
			(end 0.12065 0.2794)
			(stroke
				(width 0.1)
				(type default)
			)
			(layer "B.Fab")
		)
		(fp_line
			(start 0.67945 0.3048)
			(end 0.67945 -0.305054)
			(stroke
				(width 0.1)
				(type default)
			)
			(layer "B.Fab")
		)
		(fp_line
			(start 0.12065 0.3048)
			(end 0.67945 0.3048)
			(stroke
				(width 0.1)
				(type default)
			)
			(layer "B.Fab")
		)
		(fp_line
			(start -0.120396 0.3048)
			(end -0.120396 0.2794)
			(stroke
				(width 0.1)
				(type default)
			)
			(layer "B.Fab")
		)
		(fp_line
			(start -0.67945 0.3048)
			(end -0.120396 0.3048)
			(stroke
				(width 0.1)
				(type default)
			)
			(layer "B.Fab")
		)
		(pad "1" smd rect
			(at 0.40005 0 90)
			(size 0.4572 0.508)
			(layers "B.Cu" "B.Mask" "B.Paste")
			(net "P52V_HS2_GATE_R1")
		)
		(pad "2" smd rect
			(at -0.40005 0 90)
			(size 0.4572 0.508)
			(layers "B.Cu" "B.Mask" "B.Paste")
			(net "P52V_HS2_4287_GATE_R")
		)
	)
	(footprint ""
		(layer "B.Cu")
		(at 426.593 -35.941)
		(property "Reference" "R5932"
			(at 0 0 0)
			(layer "B.SilkS")
			(hide yes)
			(effects
				(font
					(size 1.27 1.27)
				)
				(justify mirror)
			)
		)
		(property "Value" ""
			(at 0 0 0)
			(layer "B.Fab")
			(effects
				(font
					(size 1.27 1.27)
				)
				(justify mirror)
			)
		)
		(duplicate_pad_numbers_are_jumpers no)
		(fp_line
			(start -0.7874 -0.4064)
			(end -0.7874 0.4064)
			(stroke
				(width 0.1524)
				(type default)
			)
			(layer "B.SilkS")
		)
		(fp_line
			(start -0.7874 0.4064)
			(end 0.7874 0.4064)
			(stroke
				(width 0.1524)
				(type default)
			)
			(layer "B.SilkS")
		)
		(fp_line
			(start 0.7874 -0.4064)
			(end -0.7874 -0.4064)
			(stroke
				(width 0.1524)
				(type default)
			)
			(layer "B.SilkS")
		)
		(fp_line
			(start 0.7874 0.4064)
			(end 0.7874 -0.4064)
			(stroke
				(width 0.1524)
				(type default)
			)
			(layer "B.SilkS")
		)
		(fp_line
			(start -0.67945 -0.3048)
			(end -0.67945 0.3048)
			(stroke
				(width 0.1)
				(type default)
			)
			(layer "B.Fab")
		)
		(fp_line
			(start -0.67945 0.3048)
			(end -0.120396 0.3048)
			(stroke
				(width 0.1)
				(type default)
			)
			(layer "B.Fab")
		)
		(fp_line
			(start -0.12065 -0.3048)
			(end -0.67945 -0.3048)
			(stroke
				(width 0.1)
				(type default)
			)
			(layer "B.Fab")
		)
		(fp_line
			(start -0.12065 -0.2794)
			(end -0.12065 -0.3048)
			(stroke
				(width 0.1)
				(type default)
			)
			(layer "B.Fab")
		)
		(fp_line
			(start -0.120396 0.2794)
			(end 0.12065 0.2794)
			(stroke
				(width 0.1)
				(type default)
			)
			(layer "B.Fab")
		)
		(fp_line
			(start -0.120396 0.3048)
			(end -0.120396 0.2794)
			(stroke
				(width 0.1)
				(type default)
			)
			(layer "B.Fab")
		)
		(fp_line
			(start 0.12065 -0.305054)
			(end 0.12065 -0.2794)
			(stroke
				(width 0.1)
				(type default)
			)
			(layer "B.Fab")
		)
		(fp_line
			(start 0.12065 -0.2794)
			(end -0.12065 -0.2794)
			(stroke
				(width 0.1)
				(type default)
			)
			(layer "B.Fab")
		)
		(fp_line
			(start 0.12065 0.2794)
			(end 0.12065 0.3048)
			(stroke
				(width 0.1)
				(type default)
			)
			(layer "B.Fab")
		)
		(fp_line
			(start 0.12065 0.3048)
			(end 0.67945 0.3048)
			(stroke
				(width 0.1)
				(type default)
			)
			(layer "B.Fab")
		)
		(fp_line
			(start 0.67945 -0.305054)
			(end 0.12065 -0.305054)
			(stroke
				(width 0.1)
				(type default)
			)
			(layer "B.Fab")
		)
		(fp_line
			(start 0.67945 0.3048)
			(end 0.67945 -0.305054)
			(stroke
				(width 0.1)
				(type default)
			)
			(layer "B.Fab")
		)
		(pad "1" smd circle
			(at 0.40005 0 180)
			(size 0 0)
			(layers "B.Cu" "B.Mask" "B.Paste")
			(net "SMB_PDB_MISC_SDA")
		)
		(pad "2" smd circle
			(at -0.40005 0 180)
			(size 0 0)
			(layers "B.Cu" "B.Mask" "B.Paste")
			(net "SMB_IOEXP_2_SDA")
		)
	)
	(footprint ""
		(layer "B.Cu")
		(at 295.0464 -60.833)
		(property "Reference" "PC3"
			(at 0 0 0)
			(layer "B.SilkS")
			(hide yes)
			(effects
				(font
					(size 1.27 1.27)
				)
				(justify mirror)
			)
		)
		(property "Value" ""
			(at 0 0 0)
			(layer "B.Fab")
			(effects
				(font
					(size 1.27 1.27)
				)
				(justify mirror)
			)
		)
		(duplicate_pad_numbers_are_jumpers no)
		(fp_line
			(start -2.2098 -0.9398)
			(end -2.2098 0.9398)
			(stroke
				(width 0.1524)
				(type default)
			)
			(layer "B.SilkS")
		)
		(fp_line
			(start -2.2098 0.9398)
			(end 2.2098 0.9398)
			(stroke
				(width 0.1524)
				(type default)
			)
			(layer "B.SilkS")
		)
		(fp_line
			(start 2.2098 -0.9398)
			(end -2.2098 -0.9398)
			(stroke
				(width 0.1524)
				(type default)
			)
			(layer "B.SilkS")
		)
		(fp_line
			(start 2.2098 0.9398)
			(end 2.2098 -0.9398)
			(stroke
				(width 0.1524)
				(type default)
			)
			(layer "B.SilkS")
		)
		(fp_line
			(start -2.1082 -0.8382)
			(end -2.1082 0.8382)
			(stroke
				(width 0.1)
				(type default)
			)
			(layer "B.Fab")
		)
		(fp_line
			(start -2.1082 0.8382)
			(end -1.6764 0.8382)
			(stroke
				(width 0.1)
				(type default)
			)
			(layer "B.Fab")
		)
		(fp_line
			(start -1.6764 -0.9398)
			(end -1.6764 -0.889)
			(stroke
				(width 0.1)
				(type default)
			)
			(layer "B.Fab")
		)
		(fp_line
			(start -1.6764 -0.889)
			(end -1.6764 -0.8382)
			(stroke
				(width 0.1)
				(type default)
			)
			(layer "B.Fab")
		)
		(fp_line
			(start -1.6764 -0.8382)
			(end -2.1082 -0.8382)
			(stroke
				(width 0.1)
				(type default)
			)
			(layer "B.Fab")
		)
		(fp_line
			(start -1.6764 0.8382)
			(end -1.6764 0.889)
			(stroke
				(width 0.1)
				(type default)
			)
			(layer "B.Fab")
		)
		(fp_line
			(start -1.6764 0.889)
			(end -1.6764 0.9398)
			(stroke
				(width 0.1)
				(type default)
			)
			(layer "B.Fab")
		)
		(fp_line
			(start -1.6764 0.9398)
			(end 1.6764 0.9398)
			(stroke
				(width 0.1)
				(type default)
			)
			(layer "B.Fab")
		)
		(fp_line
			(start 1.6764 -0.9398)
			(end -1.6764 -0.9398)
			(stroke
				(width 0.1)
				(type default)
			)
			(layer "B.Fab")
		)
		(fp_line
			(start 1.6764 -0.889)
			(end 1.6764 -0.9398)
			(stroke
				(width 0.1)
				(type default)
			)
			(layer "B.Fab")
		)
		(fp_line
			(start 1.6764 -0.8382)
			(end 1.6764 -0.889)
			(stroke
				(width 0.1)
				(type default)
			)
			(layer "B.Fab")
		)
		(fp_line
			(start 1.6764 0.8382)
			(end 2.1082 0.8382)
			(stroke
				(width 0.1)
				(type default)
			)
			(layer "B.Fab")
		)
		(fp_line
			(start 1.6764 0.889)
			(end 1.6764 0.8382)
			(stroke
				(width 0.1)
				(type default)
			)
			(layer "B.Fab")
		)
		(fp_line
			(start 1.6764 0.9398)
			(end 1.6764 0.889)
			(stroke
				(width 0.1)
				(type default)
			)
			(layer "B.Fab")
		)
		(fp_line
			(start 2.1082 -0.8382)
			(end 1.6764 -0.8382)
			(stroke
				(width 0.1)
				(type default)
			)
			(layer "B.Fab")
		)
		(fp_line
			(start 2.1082 0.8382)
			(end 2.1082 -0.8382)
			(stroke
				(width 0.1)
				(type default)
			)
			(layer "B.Fab")
		)
		(pad "1" smd rect
			(at 1.4732 0)
			(size 1.1684 1.5748)
			(layers "B.Cu" "B.Mask" "B.Paste")
			(net "P52V_1")
		)
		(pad "2" smd rect
			(at -1.4732 0)
			(size 1.1684 1.5748)
			(layers "B.Cu" "B.Mask" "B.Paste")
			(net "GND_FIELD_SIGNAL")
		)
	)
	(footprint ""
		(layer "B.Cu")
		(at 414.842198 -24.468836)
		(property "Reference" "C95"
			(at 0 0 0)
			(layer "B.SilkS")
			(hide yes)
			(effects
				(font
					(size 1.27 1.27)
				)
				(justify mirror)
			)
		)
		(property "Value" ""
			(at 0 0 0)
			(layer "B.Fab")
			(effects
				(font
					(size 1.27 1.27)
				)
				(justify mirror)
			)
		)
		(duplicate_pad_numbers_are_jumpers no)
		(fp_line
			(start -1.524 -0.762)
			(end -1.524 0.762)
			(stroke
				(width 0.1524)
				(type default)
			)
			(layer "B.SilkS")
		)
		(fp_line
			(start -1.524 0.762)
			(end 1.524 0.762)
			(stroke
				(width 0.1524)
				(type default)
			)
			(layer "B.SilkS")
		)
		(fp_line
			(start 1.524 -0.762)
			(end -1.524 -0.762)
			(stroke
				(width 0.1524)
				(type default)
			)
			(layer "B.SilkS")
		)
		(fp_line
			(start 1.524 0.762)
			(end 1.524 -0.762)
			(stroke
				(width 0.1524)
				(type default)
			)
			(layer "B.SilkS")
		)
		(fp_line
			(start -1.1049 -0.724916)
			(end 1.1049 -0.724916)
			(stroke
				(width 0.1)
				(type default)
			)
			(layer "B.Fab")
		)
		(fp_line
			(start -1.1049 0.724916)
			(end -1.1049 -0.724916)
			(stroke
				(width 0.1)
				(type default)
			)
			(layer "B.Fab")
		)
		(fp_line
			(start 1.1049 -0.724916)
			(end 1.1049 0.724916)
			(stroke
				(width 0.1)
				(type default)
			)
			(layer "B.Fab")
		)
		(fp_line
			(start 1.1049 0.724916)
			(end -1.1049 0.724916)
			(stroke
				(width 0.1)
				(type default)
			)
			(layer "B.Fab")
		)
		(pad "1" smd rect
			(at 0.889 0)
			(size 1.016 1.27)
			(layers "B.Cu" "B.Mask" "B.Paste")
			(net "P12V_FAN_LED")
		)
		(pad "2" smd rect
			(at -0.889 0)
			(size 1.016 1.27)
			(layers "B.Cu" "B.Mask" "B.Paste")
			(net "GND")
		)
	)
	(footprint ""
		(layer "B.Cu")
		(at 176.449736 -76.708 180)
		(property "Reference" "PR7029"
			(at 0 0 0)
			(layer "B.SilkS")
			(hide yes)
			(effects
				(font
					(size 1.27 1.27)
				)
				(justify mirror)
			)
		)
		(property "Value" ""
			(at 0 0 0)
			(layer "B.Fab")
			(effects
				(font
					(size 1.27 1.27)
				)
				(justify mirror)
			)
		)
		(duplicate_pad_numbers_are_jumpers no)
		(fp_line
			(start 0.7874 0.4064)
			(end 0.7874 -0.4064)
			(stroke
				(width 0.1524)
				(type default)
			)
			(layer "B.SilkS")
		)
		(fp_line
			(start 0.7874 -0.4064)
			(end -0.7874 -0.4064)
			(stroke
				(width 0.1524)
				(type default)
			)
			(layer "B.SilkS")
		)
		(fp_line
			(start -0.7874 0.4064)
			(end 0.7874 0.4064)
			(stroke
				(width 0.1524)
				(type default)
			)
			(layer "B.SilkS")
		)
		(fp_line
			(start -0.7874 -0.4064)
			(end -0.7874 0.4064)
			(stroke
				(width 0.1524)
				(type default)
			)
			(layer "B.SilkS")
		)
		(fp_line
			(start 0.67945 0.3048)
			(end 0.67945 -0.305054)
			(stroke
				(width 0.1)
				(type default)
			)
			(layer "B.Fab")
		)
		(fp_line
			(start 0.67945 -0.305054)
			(end 0.12065 -0.305054)
			(stroke
				(width 0.1)
				(type default)
			)
			(layer "B.Fab")
		)
		(fp_line
			(start 0.12065 0.3048)
			(end 0.67945 0.3048)
			(stroke
				(width 0.1)
				(type default)
			)
			(layer "B.Fab")
		)
		(fp_line
			(start 0.12065 0.2794)
			(end 0.12065 0.3048)
			(stroke
				(width 0.1)
				(type default)
			)
			(layer "B.Fab")
		)
		(fp_line
			(start 0.12065 -0.2794)
			(end -0.12065 -0.2794)
			(stroke
				(width 0.1)
				(type default)
			)
			(layer "B.Fab")
		)
		(fp_line
			(start 0.12065 -0.305054)
			(end 0.12065 -0.2794)
			(stroke
				(width 0.1)
				(type default)
			)
			(layer "B.Fab")
		)
		(fp_line
			(start -0.120396 0.3048)
			(end -0.120396 0.2794)
			(stroke
				(width 0.1)
				(type default)
			)
			(layer "B.Fab")
		)
		(fp_line
			(start -0.120396 0.2794)
			(end 0.12065 0.2794)
			(stroke
				(width 0.1)
				(type default)
			)
			(layer "B.Fab")
		)
		(fp_line
			(start -0.12065 -0.2794)
			(end -0.12065 -0.3048)
			(stroke
				(width 0.1)
				(type default)
			)
			(layer "B.Fab")
		)
		(fp_line
			(start -0.12065 -0.3048)
			(end -0.67945 -0.3048)
			(stroke
				(width 0.1)
				(type default)
			)
			(layer "B.Fab")
		)
		(fp_line
			(start -0.67945 0.3048)
			(end -0.120396 0.3048)
			(stroke
				(width 0.1)
				(type default)
			)
			(layer "B.Fab")
		)
		(fp_line
			(start -0.67945 -0.3048)
			(end -0.67945 0.3048)
			(stroke
				(width 0.1)
				(type default)
			)
			(layer "B.Fab")
		)
		(pad "1" smd circle
			(at 0.40005 0)
			(size 0 0)
			(layers "B.Cu" "B.Mask" "B.Paste")
			(net "PWRGD_P52V_HS2_PG")
		)
		(pad "2" smd circle
			(at -0.40005 0)
			(size 0 0)
			(layers "B.Cu" "B.Mask" "B.Paste")
			(net "P52V_HS2_PWRGIN")
		)
	)
	(footprint ""
		(layer "B.Cu")
		(at 159.685736 -61.722 180)
		(property "Reference" "U32"
			(at -2.112264 2.38633 0)
			(unlocked yes)
			(layer "B.SilkS")
			(effects
				(font
					(size 0.7874 0.5842)
					(thickness 0.1524)
				)
				(justify left mirror)
			)
		)
		(property "Value" ""
			(at 0 0 0)
			(layer "B.Fab")
			(effects
				(font
					(size 1.27 1.27)
				)
				(justify mirror)
			)
		)
		(duplicate_pad_numbers_are_jumpers no)
		(fp_line
			(start 2.249932 1.549908)
			(end -2.249932 1.549908)
			(stroke
				(width 0.1524)
				(type default)
			)
			(layer "B.SilkS")
		)
		(fp_line
			(start 2.249932 -1.549908)
			(end 2.249932 1.549908)
			(stroke
				(width 0.1524)
				(type default)
			)
			(layer "B.SilkS")
		)
		(fp_line
			(start 0.737108 -1.549908)
			(end 2.249932 -1.549908)
			(stroke
				(width 0.1524)
				(type default)
			)
			(layer "B.SilkS")
		)
		(fp_line
			(start 0 -0.8128)
			(end 0.737108 -1.549908)
			(stroke
				(width 0.1524)
				(type default)
			)
			(layer "B.SilkS")
		)
		(fp_line
			(start -0.737108 -1.549908)
			(end 0 -0.8128)
			(stroke
				(width 0.1524)
				(type default)
			)
			(layer "B.SilkS")
		)
		(fp_line
			(start -2.249932 1.549908)
			(end -2.249932 -1.549908)
			(stroke
				(width 0.1524)
				(type default)
			)
			(layer "B.SilkS")
		)
		(fp_line
			(start -2.249932 -1.549908)
			(end -0.737108 -1.549908)
			(stroke
				(width 0.1524)
				(type default)
			)
			(layer "B.SilkS")
		)
		(fp_poly
			(pts
				(xy 4.7498 -0.467106) (xy 4.7498 -1.483106) (xy 3.7338 -0.975106)
			)
			(stroke
				(width 0)
				(type default)
			)
			(fill yes)
			(layer "B.SilkS")
		)
		(fp_line
			(start 2.249932 1.549908)
			(end -2.249932 1.549908)
			(stroke
				(width 0.1)
				(type default)
			)
			(layer "B.Fab")
		)
		(fp_line
			(start 2.249932 -1.549908)
			(end 2.249932 1.549908)
			(stroke
				(width 0.1)
				(type default)
			)
			(layer "B.Fab")
		)
		(fp_line
			(start -2.249932 1.549908)
			(end -2.249932 -1.549908)
			(stroke
				(width 0.1)
				(type default)
			)
			(layer "B.Fab")
		)
		(fp_line
			(start -2.249932 -1.549908)
			(end 2.249932 -1.549908)
			(stroke
				(width 0.1)
				(type default)
			)
			(layer "B.Fab")
		)
		(fp_poly
			(pts
				(xy 4.7498 -0.467106) (xy 4.7498 -1.483106) (xy 3.7338 -0.975106)
			)
			(stroke
				(width 0)
				(type default)
			)
			(fill yes)
			(layer "B.Fab")
		)
		(pad "1" smd rect
			(at 3.052572 -0.975106 90)
			(size 0.381 1.1684)
			(layers "B.Cu" "B.Mask" "B.Paste")
			(net "P52V_HS2_CS")
		)
		(pad "2" smd rect
			(at 3.052572 -0.32512 90)
			(size 0.381 1.1684)
			(layers "B.Cu" "B.Mask" "B.Paste")
			(net "P52V_HS2_SIO")
		)
		(pad "3" smd rect
			(at 3.052572 0.32512 90)
			(size 0.381 1.1684)
			(layers "B.Cu" "B.Mask" "B.Paste")
			(net "P52V_HS2_DVCC")
		)
		(pad "4" smd rect
			(at 3.052572 0.975106 90)
			(size 0.381 1.1684)
			(layers "B.Cu" "B.Mask" "B.Paste")
			(net "GND")
		)
		(pad "5" smd rect
			(at -3.052572 0.975106 90)
			(size 0.381 1.1684)
			(layers "B.Cu" "B.Mask" "B.Paste")
			(net "P52V_HS2_SIO")
		)
		(pad "6" smd rect
			(at -3.052572 0.32512 90)
			(size 0.381 1.1684)
			(layers "B.Cu" "B.Mask" "B.Paste")
			(net "P52V_HS2_SCK")
		)
		(pad "7" smd rect
			(at -3.052572 -0.32512 90)
			(size 0.381 1.1684)
			(layers "B.Cu" "B.Mask" "B.Paste")
			(net "P52V_HS2_DVCC")
		)
		(pad "8" smd rect
			(at -3.052572 -0.975106 90)
			(size 0.381 1.1684)
			(layers "B.Cu" "B.Mask" "B.Paste")
			(net "P52V_HS2_DVCC")
		)
	)
)
